# BASEBOARD_FAB2 (Tioga Pass) — schematic netlist excerpt (pin names and nets, part order shuffled) for the footprints in the layout excerpt that follows; sources: Cadence DE-HDL packaged netlist, KiCad conversion of Wiwynn_Tioga_Pass_MB.brd

C2D45  CAP_A  22.0UF 4V 20% X6S  pkg 0603V  page 225 : A = PVDDQ_GHJ ; B = GND
R8D13  RES  10.0K 1% EMPTY  pkg 0402  page 125 : A = P3V3_STBY ; B = PU_ADR_TIMER_HOLD_OFF_N
C4F11  CAPP  220UF 4V 20% POSCAP  pkg 7343  page 233 : A = PVPP_GHJ ; B = GND

(kicad_pcb
	(version 20260206)
	(generator "pcbnew")
	(generator_version "10.0")
	(general
		(thickness 1.6)
		(legacy_teardrops no)
	)
	(paper "A4")
	(title_block
		(title "Wiwynn_Tioga_Pass_MB.brd")
		(comment 1 "Tioga Pass / footprints 596-598 of 4770")
	)
	(layers
		(0 "F.Cu" signal "TOP")
		(4 "In1.Cu" signal "L2GND")
		(6 "In2.Cu" signal "L3")
		(8 "In3.Cu" signal "L4GND")
		(10 "In4.Cu" signal "L5")
		(12 "In5.Cu" signal "L6GND")
		(14 "In6.Cu" signal "L7VCC")
		(16 "In7.Cu" signal "L8VCC")
		(18 "In8.Cu" signal "L9GND")
		(20 "In9.Cu" signal "L10")
		(22 "In10.Cu" signal "L11GND")
		(24 "In11.Cu" signal "L12")
		(26 "In12.Cu" signal "L13GND")
		(2 "B.Cu" signal "BOTTOM")
		(9 "F.Adhes" user "F.Adhesive")
		(11 "B.Adhes" user "B.Adhesive")
		(13 "F.Paste" user "Package Geometry/Pastemask Top")
		(15 "B.Paste" user "Package Geometry/Pastemask Bottom")
		(5 "F.SilkS" user "Ref Des/Silkscreen Top")
		(7 "B.SilkS" user "Ref Des/Silkscreen Bottom")
		(1 "F.Mask" user "Board Geometry/Soldermask Top")
		(3 "B.Mask" user "Board Geometry/Soldermask Bottom")
		(17 "Dwgs.User" user "User.Drawings")
		(19 "Cmts.User" user "User.Comments")
		(21 "Eco1.User" user "User.Eco1")
		(23 "Eco2.User" user "User.Eco2")
		(25 "Edge.Cuts" user "Board Geometry/Outline")
		(27 "Margin" user)
		(31 "F.CrtYd" user "Package Geometry/Place Bound Top")
		(29 "B.CrtYd" user "Package Geometry/Place Bound Bottom")
		(35 "F.Fab" user "Ref Des/Assembly Top")
		(33 "B.Fab" user "Ref Des/Assembly Bottom")
	)
	(footprint ""
		(layer "F.Cu")
		(at 103.400606 -68.365116 180)
		(property "Reference" "C2D45"
			(at 0 0 180)
			(layer "F.SilkS")
			(hide yes)
			(effects
				(font
					(size 1.27 1.27)
				)
			)
		)
		(property "Value" ""
			(at 0 0 180)
			(layer "F.Fab")
			(effects
				(font
					(size 1.27 1.27)
				)
			)
		)
		(duplicate_pad_numbers_are_jumpers no)
		(fp_poly
			(pts
				(xy -0.4953 -0.2032) (xy 0.4953 -0.2032) (xy 0.4953 1.6002) (xy -0.4953 1.6002)
			)
			(stroke
				(width 0)
				(type default)
			)
			(fill no)
			(layer "F.CrtYd")
		)
		(fp_line
			(start 0.4953 1.6002)
			(end -0.4953 1.6002)
			(stroke
				(width 0.1)
				(type default)
			)
			(layer "F.Fab")
		)
		(fp_line
			(start 0.4953 -0.2032)
			(end 0.4953 1.6002)
			(stroke
				(width 0.1)
				(type default)
			)
			(layer "F.Fab")
		)
		(fp_line
			(start -0.4953 1.6002)
			(end -0.4953 -0.2032)
			(stroke
				(width 0.1)
				(type default)
			)
			(layer "F.Fab")
		)
		(fp_line
			(start -0.4953 -0.2032)
			(end 0.4953 -0.2032)
			(stroke
				(width 0.1)
				(type default)
			)
			(layer "F.Fab")
		)
		(pad "1" smd rect
			(at 0 0 180)
			(size 0.762 0.889)
			(layers "F.Cu" "F.Mask" "F.Paste")
			(net "PVDDQ_GHJ")
		)
		(pad "2" smd rect
			(at 0 1.397 180)
			(size 0.762 0.889)
			(layers "F.Cu" "F.Mask" "F.Paste")
			(net "GND")
		)
		(zone
			(layer "F.Cu")
			(hatch none 0.5)
			(connect_pads
				(clearance 0)
			)
			(min_thickness 0.25)
			(keepout
				(tracks not_allowed)
				(vias allowed)
				(pads allowed)
				(copperpour not_allowed)
				(footprints allowed)
			)
			(placement
				(enabled no)
				(sheetname "")
			)
			(fill
				(thermal_gap 0.5)
				(thermal_bridge_width 0.5)
				(island_removal_mode 0)
			)
			(polygon
				(pts
					(xy 103.781606 -68.809616) (xy 103.019606 -68.809616) (xy 103.019606 -69.317616) (xy 103.781606 -69.317616)
				)
			)
		)
	)
	(footprint ""
		(layer "F.Cu")
		(at 166.8272 -20.828 90)
		(property "Reference" "C4F11"
			(at 2.89433 0.6858 0)
			(unlocked yes)
			(layer "F.SilkS")
			(effects
				(font
					(size 0.7874 0.5842)
					(thickness 0.1524)
				)
				(justify left)
			)
		)
		(property "Value" ""
			(at 0 0 90)
			(layer "F.Fab")
			(effects
				(font
					(size 1.27 1.27)
				)
			)
		)
		(duplicate_pad_numbers_are_jumpers no)
		(fp_line
			(start 2.032 -1.524)
			(end 2.032 1.524)
			(stroke
				(width 0.1524)
				(type default)
			)
			(layer "F.SilkS")
		)
		(fp_line
			(start 1.7272 -1.524)
			(end 2.032 -1.524)
			(stroke
				(width 0.1524)
				(type default)
			)
			(layer "F.SilkS")
		)
		(fp_line
			(start -1.7272 -1.524)
			(end -2.032 -1.524)
			(stroke
				(width 0.1524)
				(type default)
			)
			(layer "F.SilkS")
		)
		(fp_line
			(start -2.032 -1.524)
			(end -2.032 1.524)
			(stroke
				(width 0.1524)
				(type default)
			)
			(layer "F.SilkS")
		)
		(fp_line
			(start 2.2987 -0.2413)
			(end 2.032 -0.2413)
			(stroke
				(width 0.1524)
				(type default)
			)
			(layer "F.SilkS")
		)
		(fp_line
			(start -2.032 -0.2413)
			(end -2.2987 -0.2413)
			(stroke
				(width 0.1524)
				(type default)
			)
			(layer "F.SilkS")
		)
		(fp_line
			(start -2.2987 -0.2413)
			(end -2.2987 7.3533)
			(stroke
				(width 0.1524)
				(type default)
			)
			(layer "F.SilkS")
		)
		(fp_line
			(start 2.032 1.524)
			(end 1.7272 1.524)
			(stroke
				(width 0.1524)
				(type default)
			)
			(layer "F.SilkS")
		)
		(fp_line
			(start -2.032 1.524)
			(end -1.7272 1.524)
			(stroke
				(width 0.1524)
				(type default)
			)
			(layer "F.SilkS")
		)
		(fp_line
			(start 2.2987 7.3533)
			(end 2.2987 -0.2413)
			(stroke
				(width 0.1524)
				(type default)
			)
			(layer "F.SilkS")
		)
		(fp_line
			(start 1.7272 7.3533)
			(end 2.2987 7.3533)
			(stroke
				(width 0.1524)
				(type default)
			)
			(layer "F.SilkS")
		)
		(fp_line
			(start -2.2987 7.3533)
			(end -1.7272 7.3533)
			(stroke
				(width 0.1524)
				(type default)
			)
			(layer "F.SilkS")
		)
		(fp_rect
			(start -2.2987 -0.2413)
			(end 2.2987 7.3533)
			(stroke
				(width 0)
				(type default)
			)
			(fill no)
			(layer "F.CrtYd")
		)
		(fp_line
			(start 2.2987 -0.2413)
			(end 2.2987 7.3533)
			(stroke
				(width 0.1)
				(type default)
			)
			(layer "F.Fab")
		)
		(fp_line
			(start -2.2987 -0.2413)
			(end 2.2987 -0.2413)
			(stroke
				(width 0.1)
				(type default)
			)
			(layer "F.Fab")
		)
		(fp_line
			(start 2.2987 7.3533)
			(end -2.2987 7.3533)
			(stroke
				(width 0.1)
				(type default)
			)
			(layer "F.Fab")
		)
		(fp_line
			(start -2.2987 7.3533)
			(end -2.2987 -0.2413)
			(stroke
				(width 0.1)
				(type default)
			)
			(layer "F.Fab")
		)
		(pad "1" smd rect
			(at 0 0 90)
			(size 2.54 3.048)
			(layers "F.Cu" "F.Mask" "F.Paste")
			(net "PVPP_GHJ")
		)
		(pad "2" smd rect
			(at 0 7.112 90)
			(size 2.54 3.048)
			(layers "F.Cu" "F.Mask" "F.Paste")
			(net "GND")
		)
	)
	(footprint ""
		(layer "F.Cu")
		(at 391.795 -88.2015)
		(property "Reference" "R8D13"
			(at 0 0 0)
			(layer "F.SilkS")
			(hide yes)
			(effects
				(font
					(size 1.27 1.27)
				)
			)
		)
		(property "Value" ""
			(at 0 0 0)
			(layer "F.Fab")
			(effects
				(font
					(size 1.27 1.27)
				)
			)
		)
		(duplicate_pad_numbers_are_jumpers no)
		(fp_poly
			(pts
				(xy -0.2794 -0.1016) (xy 0.2794 -0.1016) (xy 0.2794 0.9906) (xy -0.2794 0.9906)
			)
			(stroke
				(width 0)
				(type default)
			)
			(fill no)
			(layer "F.CrtYd")
		)
		(fp_line
			(start -0.2794 -0.1016)
			(end -0.2794 0.9906)
			(stroke
				(width 0.1)
				(type default)
			)
			(layer "F.Fab")
		)
		(fp_line
			(start -0.2794 0.9906)
			(end 0.2794 0.9906)
			(stroke
				(width 0.1)
				(type default)
			)
			(layer "F.Fab")
		)
		(fp_line
			(start 0.2794 -0.1016)
			(end -0.2794 -0.1016)
			(stroke
				(width 0.1)
				(type default)
			)
			(layer "F.Fab")
		)
		(fp_line
			(start 0.2794 0.9906)
			(end 0.2794 -0.1016)
			(stroke
				(width 0.1)
				(type default)
			)
			(layer "F.Fab")
		)
		(pad "1" smd rect
			(at 0 0)
			(size 0.508 0.508)
			(layers "F.Cu" "F.Mask" "F.Paste")
			(net "P3V3_STBY")
		)
		(pad "2" smd rect
			(at 0 0.889)
			(size 0.508 0.508)
			(layers "F.Cu" "F.Mask" "F.Paste")
			(net "PU_ADR_TIMER_HOLD_OFF_N")
		)
		(zone
			(layer "F.Cu")
			(hatch none 0.5)
			(connect_pads
				(clearance 0)
			)
			(min_thickness 0.25)
			(keepout
				(tracks allowed)
				(vias not_allowed)
				(pads allowed)
				(copperpour not_allowed)
				(footprints allowed)
			)
			(placement
				(enabled no)
				(sheetname "")
			)
			(fill
				(thermal_gap 0.5)
				(thermal_bridge_width 0.5)
				(island_removal_mode 0)
			)
			(polygon
				(pts
					(xy 391.541 -87.9475) (xy 392.049 -87.9475) (xy 392.049 -87.5665) (xy 391.541 -87.5665)
				)
			)
		)
		(zone
			(layer "F.Cu")
			(hatch none 0.5)
			(connect_pads
				(clearance 0)
			)
			(min_thickness 0.25)
			(keepout
				(tracks not_allowed)
				(vias allowed)
				(pads allowed)
				(copperpour not_allowed)
				(footprints allowed)
			)
			(placement
				(enabled no)
				(sheetname "")
			)
			(fill
				(thermal_gap 0.5)
				(thermal_bridge_width 0.5)
				(island_removal_mode 0)
			)
			(polygon
				(pts
					(xy 391.541 -87.5665) (xy 392.049 -87.5665) (xy 392.049 -87.9475) (xy 391.541 -87.9475)
				)
			)
		)
	)
)
